# BASEBOARD_FAB2 (Tioga Pass) — schematic netlist excerpt (pin names and nets, part order shuffled) for the footprints in the layout excerpt that follows; sources: Cadence DE-HDL packaged netlist, KiCad conversion of Wiwynn_Tioga_Pass_MB.brd

C4C4  SC1U10V2KX-4-GP  10%  pkg SMD-BCG6  page 205 : \1\ = P5V_STBY ; \2\ = GND
C5P34  CAP  47UF 4V 20% X6S  pkg 0805  page 42 : A = PVCCIN_CPU0 ; B = GND

(kicad_pcb
	(version 20260206)
	(generator "pcbnew")
	(generator_version "10.0")
	(general
		(thickness 1.6)
		(legacy_teardrops no)
	)
	(paper "A4")
	(title_block
		(title "Wiwynn_Tioga_Pass_MB.brd")
		(comment 1 "Tioga Pass / footprints 2715-2716 of 4770")
	)
	(layers
		(0 "F.Cu" signal "TOP")
		(4 "In1.Cu" signal "L2GND")
		(6 "In2.Cu" signal "L3")
		(8 "In3.Cu" signal "L4GND")
		(10 "In4.Cu" signal "L5")
		(12 "In5.Cu" signal "L6GND")
		(14 "In6.Cu" signal "L7VCC")
		(16 "In7.Cu" signal "L8VCC")
		(18 "In8.Cu" signal "L9GND")
		(20 "In9.Cu" signal "L10")
		(22 "In10.Cu" signal "L11GND")
		(24 "In11.Cu" signal "L12")
		(26 "In12.Cu" signal "L13GND")
		(2 "B.Cu" signal "BOTTOM")
		(9 "F.Adhes" user "F.Adhesive")
		(11 "B.Adhes" user "B.Adhesive")
		(13 "F.Paste" user "Package Geometry/Pastemask Top")
		(15 "B.Paste" user "Package Geometry/Pastemask Bottom")
		(5 "F.SilkS" user "Ref Des/Silkscreen Top")
		(7 "B.SilkS" user "Ref Des/Silkscreen Bottom")
		(1 "F.Mask" user "Board Geometry/Soldermask Top")
		(3 "B.Mask" user "Board Geometry/Soldermask Bottom")
		(17 "Dwgs.User" user "User.Drawings")
		(19 "Cmts.User" user "User.Comments")
		(21 "Eco1.User" user "User.Eco1")
		(23 "Eco2.User" user "User.Eco2")
		(25 "Edge.Cuts" user "Board Geometry/Outline")
		(27 "Margin" user)
		(31 "F.CrtYd" user "Package Geometry/Place Bound Top")
		(29 "B.CrtYd" user "Package Geometry/Place Bound Bottom")
		(35 "F.Fab" user "Ref Des/Assembly Top")
		(33 "B.Fab" user "Ref Des/Assembly Bottom")
	)
	(footprint ""
		(layer "B.Cu")
		(at 198.605648 -93.835982 90)
		(property "Reference" "C4C4"
			(at 0 0 90)
			(layer "B.SilkS")
			(hide yes)
			(effects
				(font
					(size 1.27 1.27)
				)
				(justify mirror)
			)
		)
		(property "Value" "*"
			(at -1.1811 -2.8194 90)
			(unlocked yes)
			(layer "B.Fab")
			(hide yes)
			(effects
				(font
					(size 1.27 1.016)
					(thickness 0.1524)
				)
				(justify mirror)
			)
		)
		(property "Device Type" "SC1U10V2KX-4-GP_SMD-BCG6-SC1U1A"
			(at -1.1811 -4.3434 90)
			(unlocked yes)
			(layer "B.Fab")
			(hide yes)
			(effects
				(font
					(size 1.27 1.016)
					(thickness 0.1524)
				)
				(justify mirror)
			)
		)
		(duplicate_pad_numbers_are_jumpers no)
		(fp_rect
			(start 0.4318 0.9525)
			(end -0.4318 -0.9525)
			(stroke
				(width 0)
				(type default)
			)
			(fill no)
			(layer "B.CrtYd")
		)
		(fp_rect
			(start 0.4318 0.9525)
			(end -0.4318 -0.9525)
			(stroke
				(width 0)
				(type default)
			)
			(fill no)
			(layer "B.Fab")
		)
		(pad "1" smd custom
			(at 0 -0.4445 270)
			(size 0.1524 0.1524)
			(layers "B.Cu" "B.Mask" "B.Paste")
			(net "P5V_STBY")
			(options
				(clearance outline)
				(anchor circle)
			)
			(primitives
				(gr_poly
					(pts
						(arc
							(start 0.3048 0.2032)
							(mid 0.275042 0.275042)
							(end 0.2032 0.3048)
						)
						(arc
							(start -0.2032 0.3048)
							(mid -0.275042 0.275042)
							(end -0.3048 0.2032)
						)
						(arc
							(start -0.3048 -0.2032)
							(mid -0.275042 -0.275042)
							(end -0.2032 -0.3048)
						)
						(arc
							(start 0.2032 -0.3048)
							(mid 0.275042 -0.275042)
							(end 0.3048 -0.2032)
						)
					)
					(width 0)
					(fill yes)
				)
			)
		)
		(pad "2" smd custom
			(at 0 0.4445 270)
			(size 0.1524 0.1524)
			(layers "B.Cu" "B.Mask" "B.Paste")
			(net "GND")
			(options
				(clearance outline)
				(anchor circle)
			)
			(primitives
				(gr_poly
					(pts
						(arc
							(start 0.3048 0.2032)
							(mid 0.275042 0.275042)
							(end 0.2032 0.3048)
						)
						(arc
							(start -0.2032 0.3048)
							(mid -0.275042 0.275042)
							(end -0.3048 0.2032)
						)
						(arc
							(start -0.3048 -0.2032)
							(mid -0.275042 -0.275042)
							(end -0.2032 -0.3048)
						)
						(arc
							(start 0.2032 -0.3048)
							(mid 0.275042 -0.275042)
							(end 0.3048 -0.2032)
						)
					)
					(width 0)
					(fill yes)
				)
			)
		)
	)
	(footprint ""
		(layer "B.Cu")
		(at 264.035286 -73.51014)
		(property "Reference" "C5P34"
			(at 0 0 0)
			(layer "B.SilkS")
			(hide yes)
			(effects
				(font
					(size 1.27 1.27)
				)
				(justify mirror)
			)
		)
		(property "Value" ""
			(at 0 0 0)
			(layer "B.Fab")
			(effects
				(font
					(size 1.27 1.27)
				)
				(justify mirror)
			)
		)
		(duplicate_pad_numbers_are_jumpers no)
		(fp_poly
			(pts
				(xy 0.7239 -0.2159) (xy -0.7239 -0.2159) (xy -0.7239 1.9939) (xy 0.7239 1.9939)
			)
			(stroke
				(width 0)
				(type default)
			)
			(fill no)
			(layer "B.CrtYd")
		)
		(fp_line
			(start -0.7239 -0.2159)
			(end 0.7239 -0.2159)
			(stroke
				(width 0.1)
				(type default)
			)
			(layer "B.Fab")
		)
		(fp_line
			(start -0.7239 1.9939)
			(end -0.7239 -0.2159)
			(stroke
				(width 0.1)
				(type default)
			)
			(layer "B.Fab")
		)
		(fp_line
			(start 0.7239 -0.2159)
			(end 0.7239 1.9939)
			(stroke
				(width 0.1)
				(type default)
			)
			(layer "B.Fab")
		)
		(fp_line
			(start 0.7239 1.9939)
			(end -0.7239 1.9939)
			(stroke
				(width 0.1)
				(type default)
			)
			(layer "B.Fab")
		)
		(pad "1" smd rect
			(at 0 0 180)
			(size 1.27 1.016)
			(layers "B.Cu" "B.Mask" "B.Paste")
			(net "PVCCIN_CPU0")
		)
		(pad "2" smd rect
			(at 0 1.778 180)
			(size 1.27 1.016)
			(layers "B.Cu" "B.Mask" "B.Paste")
			(net "GND")
		)
		(zone
			(layer "B.Cu")
			(hatch none 0.5)
			(connect_pads
				(clearance 0)
			)
			(min_thickness 0.25)
			(keepout
				(tracks not_allowed)
				(vias allowed)
				(pads allowed)
				(copperpour not_allowed)
				(footprints allowed)
			)
			(placement
				(enabled no)
				(sheetname "")
			)
			(fill
				(thermal_gap 0.5)
				(thermal_bridge_width 0.5)
				(island_removal_mode 0)
			)
			(polygon
				(pts
					(xy 264.670286 -73.00214) (xy 263.400286 -73.00214) (xy 263.400286 -72.24014) (xy 264.670286 -72.24014)
				)
			)
		)
	)
)
